# T6G (Grand Teton) — schematic netlist excerpt (pin names and nets, part order shuffled) for the footprints in the layout excerpt that follows; sources: Cadence DE-HDL packaged netlist, KiCad conversion of 04192023_DAF0TMB3IC0_F0TG_MB_C_brd_V02_OCP.brd

C1175  Q_CAP  0.1UF 16V 10% X7R  pkg C0402  page 83 : A = P3V3_AUX ; B = GND
R4546  Q_RES  100K 1% EMPTY  pkg 0402LF  page 124 : A = P3V3_AUX ; B = HGX_DETECT_N_ISO

(kicad_pcb
	(version 20260206)
	(generator "pcbnew")
	(generator_version "10.0")
	(general
		(thickness 1.6)
		(legacy_teardrops no)
	)
	(paper "A4")
	(title_block
		(title "04192023_DAF0TMB3IC0_F0TG_MB_C_brd_V02_OCP.brd")
		(comment 1 "Grand Teton / footprints 5330-5331 of 8354")
	)
	(layers
		(0 "F.Cu" signal "TOP")
		(4 "In1.Cu" signal "GND")
		(6 "In2.Cu" signal "IN1")
		(8 "In3.Cu" signal "GND1")
		(10 "In4.Cu" signal "IN2")
		(12 "In5.Cu" signal "GND2")
		(14 "In6.Cu" signal "IN3")
		(16 "In7.Cu" signal "GND3")
		(18 "In8.Cu" signal "VCC")
		(20 "In9.Cu" signal "VCC1")
		(22 "In10.Cu" signal "GND4")
		(24 "In11.Cu" signal "IN4")
		(26 "In12.Cu" signal "GND5")
		(28 "In13.Cu" signal "IN5")
		(30 "In14.Cu" signal "GND6")
		(32 "In15.Cu" signal "IN6")
		(34 "In16.Cu" signal "GND7")
		(2 "B.Cu" signal "BOTTOM")
		(9 "F.Adhes" user "F.Adhesive")
		(11 "B.Adhes" user "B.Adhesive")
		(13 "F.Paste" user "Package Geometry/Pastemask Top")
		(15 "B.Paste" user "Package Geometry/Pastemask Bottom")
		(5 "F.SilkS" user "Ref Des/Silkscreen Top")
		(7 "B.SilkS" user "Ref Des/Silkscreen Bottom")
		(1 "F.Mask" user "Board Geometry/Soldermask Top")
		(3 "B.Mask" user "Board Geometry/Soldermask Bottom")
		(17 "Dwgs.User" user "User.Drawings")
		(19 "Cmts.User" user "User.Comments")
		(21 "Eco1.User" user "User.Eco1")
		(23 "Eco2.User" user "User.Eco2")
		(25 "Edge.Cuts" user "Board Geometry/Outline")
		(27 "Margin" user)
		(31 "F.CrtYd" user "Package Geometry/Place Bound Top")
		(29 "B.CrtYd" user "Package Geometry/Place Bound Bottom")
		(35 "F.Fab" user "Ref Des/Assembly Top")
		(33 "B.Fab" user "Ref Des/Assembly Bottom")
	)
	(footprint ""
		(layer "B.Cu")
		(at 187.111894 -112.263174 180)
		(property "Reference" "C1175"
			(at 0 0 0)
			(layer "B.SilkS")
			(hide yes)
			(effects
				(font
					(size 1.27 1.27)
				)
				(justify mirror)
			)
		)
		(property "Value" ""
			(at 0 0 0)
			(layer "B.Fab")
			(effects
				(font
					(size 1.27 1.27)
				)
				(justify mirror)
			)
		)
		(duplicate_pad_numbers_are_jumpers no)
		(fp_line
			(start 0.69215 0.2921)
			(end 0.69215 -0.2921)
			(stroke
				(width 0.1524)
				(type default)
			)
			(layer "B.SilkS")
		)
		(fp_line
			(start 0.69215 -0.2921)
			(end -0.69215 -0.2921)
			(stroke
				(width 0.1524)
				(type default)
			)
			(layer "B.SilkS")
		)
		(fp_line
			(start -0.69215 0.2921)
			(end 0.69215 0.2921)
			(stroke
				(width 0.1524)
				(type default)
			)
			(layer "B.SilkS")
		)
		(fp_line
			(start -0.69215 -0.2921)
			(end -0.69215 0.2921)
			(stroke
				(width 0.1524)
				(type default)
			)
			(layer "B.SilkS")
		)
		(fp_line
			(start 0.51435 0.2794)
			(end 0.51435 -0.2794)
			(stroke
				(width 0.1)
				(type default)
			)
			(layer "B.Fab")
		)
		(fp_line
			(start 0.51435 -0.2794)
			(end -0.51435 -0.2794)
			(stroke
				(width 0.1)
				(type default)
			)
			(layer "B.Fab")
		)
		(fp_line
			(start -0.51435 0.2794)
			(end 0.51435 0.2794)
			(stroke
				(width 0.1)
				(type default)
			)
			(layer "B.Fab")
		)
		(fp_line
			(start -0.51435 -0.2794)
			(end -0.51435 0.2794)
			(stroke
				(width 0.1)
				(type default)
			)
			(layer "B.Fab")
		)
		(pad "1" smd circle
			(at 0.40005 0)
			(size 0 0)
			(layers "B.Cu" "B.Mask" "B.Paste")
			(net "P3V3_AUX")
		)
		(pad "2" smd circle
			(at -0.40005 0)
			(size 0 0)
			(layers "B.Cu" "B.Mask" "B.Paste")
			(net "GND")
		)
		(zone
			(layer "B.Cu")
			(hatch none 0.5)
			(connect_pads
				(clearance 0)
			)
			(min_thickness 0.25)
			(keepout
				(tracks not_allowed)
				(vias allowed)
				(pads allowed)
				(copperpour not_allowed)
				(footprints allowed)
			)
			(placement
				(enabled no)
				(sheetname "")
			)
			(fill
				(thermal_gap 0.5)
				(thermal_bridge_width 0.5)
				(island_removal_mode 0)
			)
			(polygon
				(pts
					(xy 186.921394 -112.17529) (xy 186.921394 -112.350804) (xy 187.012834 -112.40897) (xy 187.212224 -112.40897)
					(xy 187.302394 -112.350804) (xy 187.302394 -112.175544) (xy 187.212224 -112.117124) (xy 187.012834 -112.117124)
				)
			)
		)
	)
	(footprint ""
		(layer "B.Cu")
		(at 104.555544 -412.832296 90)
		(property "Reference" "R4546"
			(at 0 0 90)
			(layer "B.SilkS")
			(hide yes)
			(effects
				(font
					(size 1.27 1.27)
				)
				(justify mirror)
			)
		)
		(property "Value" ""
			(at 0 0 90)
			(layer "B.Fab")
			(effects
				(font
					(size 1.27 1.27)
				)
				(justify mirror)
			)
		)
		(duplicate_pad_numbers_are_jumpers no)
		(fp_line
			(start 0.7874 -0.4064)
			(end -0.7874 -0.4064)
			(stroke
				(width 0.1524)
				(type default)
			)
			(layer "B.SilkS")
		)
		(fp_line
			(start -0.7874 -0.4064)
			(end -0.7874 0.4064)
			(stroke
				(width 0.1524)
				(type default)
			)
			(layer "B.SilkS")
		)
		(fp_line
			(start 0.7874 0.4064)
			(end 0.7874 -0.4064)
			(stroke
				(width 0.1524)
				(type default)
			)
			(layer "B.SilkS")
		)
		(fp_line
			(start -0.7874 0.4064)
			(end 0.7874 0.4064)
			(stroke
				(width 0.1524)
				(type default)
			)
			(layer "B.SilkS")
		)
		(fp_line
			(start 0.67945 -0.305054)
			(end 0.12065 -0.305054)
			(stroke
				(width 0.1)
				(type default)
			)
			(layer "B.Fab")
		)
		(fp_line
			(start 0.12065 -0.305054)
			(end 0.12065 -0.2794)
			(stroke
				(width 0.1)
				(type default)
			)
			(layer "B.Fab")
		)
		(fp_line
			(start -0.12065 -0.3048)
			(end -0.67945 -0.3048)
			(stroke
				(width 0.1)
				(type default)
			)
			(layer "B.Fab")
		)
		(fp_line
			(start -0.67945 -0.3048)
			(end -0.67945 0.3048)
			(stroke
				(width 0.1)
				(type default)
			)
			(layer "B.Fab")
		)
		(fp_line
			(start 0.12065 -0.2794)
			(end -0.12065 -0.2794)
			(stroke
				(width 0.1)
				(type default)
			)
			(layer "B.Fab")
		)
		(fp_line
			(start -0.12065 -0.2794)
			(end -0.12065 -0.3048)
			(stroke
				(width 0.1)
				(type default)
			)
			(layer "B.Fab")
		)
		(fp_line
			(start 0.12065 0.2794)
			(end 0.12065 0.3048)
			(stroke
				(width 0.1)
				(type default)
			)
			(layer "B.Fab")
		)
		(fp_line
			(start -0.120396 0.2794)
			(end 0.12065 0.2794)
			(stroke
				(width 0.1)
				(type default)
			)
			(layer "B.Fab")
		)
		(fp_line
			(start 0.67945 0.3048)
			(end 0.67945 -0.305054)
			(stroke
				(width 0.1)
				(type default)
			)
			(layer "B.Fab")
		)
		(fp_line
			(start 0.12065 0.3048)
			(end 0.67945 0.3048)
			(stroke
				(width 0.1)
				(type default)
			)
			(layer "B.Fab")
		)
		(fp_line
			(start -0.120396 0.3048)
			(end -0.120396 0.2794)
			(stroke
				(width 0.1)
				(type default)
			)
			(layer "B.Fab")
		)
		(fp_line
			(start -0.67945 0.3048)
			(end -0.120396 0.3048)
			(stroke
				(width 0.1)
				(type default)
			)
			(layer "B.Fab")
		)
		(pad "1" smd circle
			(at 0.40005 0 270)
			(size 0 0)
			(layers "B.Cu" "B.Mask" "B.Paste")
			(net "P3V3_AUX")
		)
		(pad "2" smd circle
			(at -0.40005 0 270)
			(size 0 0)
			(layers "B.Cu" "B.Mask" "B.Paste")
			(net "HGX_DETECT_N_ISO")
		)
	)
)
